# BASEBOARD_FAB2 (Tioga Pass) — schematic netlist excerpt (pin names and nets, part order shuffled) for the footprints in the layout excerpt that follows; sources: Cadence DE-HDL packaged netlist, KiCad conversion of Wiwynn_Tioga_Pass_MB.brd

DS9A2  LED  IC  pkg 1NCLF  page 177 : C = FP_LED_HDD_ACTIVITY_AND_N ; A = FP_LED_HDD_ACTIVITY_AND_R_N
R25W116  RES  3.32K 1% EMPTY  pkg 0402  page 150 : A = GND ; B = UART_BMC_TXD5

(kicad_pcb
	(version 20260206)
	(generator "pcbnew")
	(generator_version "10.0")
	(general
		(thickness 1.6)
		(legacy_teardrops no)
	)
	(paper "A4")
	(title_block
		(title "Wiwynn_Tioga_Pass_MB.brd")
		(comment 1 "Tioga Pass / footprints 1776-1777 of 4770")
	)
	(layers
		(0 "F.Cu" signal "TOP")
		(4 "In1.Cu" signal "L2GND")
		(6 "In2.Cu" signal "L3")
		(8 "In3.Cu" signal "L4GND")
		(10 "In4.Cu" signal "L5")
		(12 "In5.Cu" signal "L6GND")
		(14 "In6.Cu" signal "L7VCC")
		(16 "In7.Cu" signal "L8VCC")
		(18 "In8.Cu" signal "L9GND")
		(20 "In9.Cu" signal "L10")
		(22 "In10.Cu" signal "L11GND")
		(24 "In11.Cu" signal "L12")
		(26 "In12.Cu" signal "L13GND")
		(2 "B.Cu" signal "BOTTOM")
		(9 "F.Adhes" user "F.Adhesive")
		(11 "B.Adhes" user "B.Adhesive")
		(13 "F.Paste" user "Package Geometry/Pastemask Top")
		(15 "B.Paste" user "Package Geometry/Pastemask Bottom")
		(5 "F.SilkS" user "Ref Des/Silkscreen Top")
		(7 "B.SilkS" user "Ref Des/Silkscreen Bottom")
		(1 "F.Mask" user "Board Geometry/Soldermask Top")
		(3 "B.Mask" user "Board Geometry/Soldermask Bottom")
		(17 "Dwgs.User" user "User.Drawings")
		(19 "Cmts.User" user "User.Comments")
		(21 "Eco1.User" user "User.Eco1")
		(23 "Eco2.User" user "User.Eco2")
		(25 "Edge.Cuts" user "Board Geometry/Outline")
		(27 "Margin" user)
		(31 "F.CrtYd" user "Package Geometry/Place Bound Top")
		(29 "B.CrtYd" user "Package Geometry/Place Bound Bottom")
		(35 "F.Fab" user "Ref Des/Assembly Top")
		(33 "B.Fab" user "Ref Des/Assembly Bottom")
	)
	(footprint ""
		(layer "F.Cu")
		(at 499.872 -149.86)
		(property "Reference" "DS9A2"
			(at -1.31953 -0.28448 90)
			(unlocked yes)
			(layer "F.SilkS")
			(effects
				(font
					(size 0.7874 0.5842)
					(thickness 0.1524)
				)
			)
		)
		(property "Value" ""
			(at 0 0 0)
			(layer "F.Fab")
			(effects
				(font
					(size 1.27 1.27)
				)
			)
		)
		(duplicate_pad_numbers_are_jumpers no)
		(fp_line
			(start -1.842262 1.00711)
			(end -1.36144 0.174244)
			(stroke
				(width 0.1524)
				(type default)
			)
			(layer "F.SilkS")
		)
		(fp_line
			(start -1.36144 -0.949198)
			(end -1.36144 0.174244)
			(stroke
				(width 0.1524)
				(type default)
			)
			(layer "F.SilkS")
		)
		(fp_line
			(start -1.36144 0.174244)
			(end -0.880618 1.00711)
			(stroke
				(width 0.1524)
				(type default)
			)
			(layer "F.SilkS")
		)
		(fp_line
			(start -1.36144 1.00711)
			(end -1.842262 1.00711)
			(stroke
				(width 0.1524)
				(type default)
			)
			(layer "F.SilkS")
		)
		(fp_line
			(start -1.36144 1.918716)
			(end -1.36144 1.00711)
			(stroke
				(width 0.1524)
				(type default)
			)
			(layer "F.SilkS")
		)
		(fp_line
			(start -0.880618 0.174244)
			(end -1.842262 0.174244)
			(stroke
				(width 0.1524)
				(type default)
			)
			(layer "F.SilkS")
		)
		(fp_line
			(start -0.880618 1.00711)
			(end -1.36144 1.00711)
			(stroke
				(width 0.1524)
				(type default)
			)
			(layer "F.SilkS")
		)
		(fp_poly
			(pts
				(xy -0.5715 2.2098) (xy -0.5715 0.2032) (xy 0.5715 0.2032) (xy 0.5715 0.6985)
				(arc
					(start 0.726948 0.6985)
					(mid 1.29058 0.932279)
					(end 1.524 1.49606)
				)
				(arc
					(start 1.524 2.05994)
					(mid 1.2904 2.6239)
					(end 0.72644 2.8575)
				)
				(xy 0.5715 2.8575) (xy 0.5715 3.3528) (xy -0.5715 3.3528)
			)
			(stroke
				(width 0)
				(type default)
			)
			(fill no)
			(layer "F.CrtYd")
		)
		(fp_line
			(start -1.848612 0.973328)
			(end -1.36779 0.140462)
			(stroke
				(width 0.1)
				(type default)
			)
			(layer "F.Fab")
		)
		(fp_line
			(start -1.36779 0.140462)
			(end -1.36779 -0.98298)
			(stroke
				(width 0.1)
				(type default)
			)
			(layer "F.Fab")
		)
		(fp_line
			(start -1.36779 0.140462)
			(end -0.886968 0.973328)
			(stroke
				(width 0.1)
				(type default)
			)
			(layer "F.Fab")
		)
		(fp_line
			(start -1.36779 0.973328)
			(end -1.36779 1.884934)
			(stroke
				(width 0.1)
				(type default)
			)
			(layer "F.Fab")
		)
		(fp_line
			(start -0.886968 0.140462)
			(end -1.848612 0.140462)
			(stroke
				(width 0.1)
				(type default)
			)
			(layer "F.Fab")
		)
		(fp_line
			(start -0.886968 0.973328)
			(end -1.848612 0.973328)
			(stroke
				(width 0.1)
				(type default)
			)
			(layer "F.Fab")
		)
		(fp_line
			(start -0.5715 0.2032)
			(end 0.5715 0.2032)
			(stroke
				(width 0.1)
				(type default)
			)
			(layer "F.Fab")
		)
		(fp_line
			(start -0.5715 0.7112)
			(end 0.5715 0.7112)
			(stroke
				(width 0.1)
				(type default)
			)
			(layer "F.Fab")
		)
		(fp_line
			(start -0.5715 2.8448)
			(end 0.5715 2.8448)
			(stroke
				(width 0.1)
				(type default)
			)
			(layer "F.Fab")
		)
		(fp_line
			(start -0.5715 3.3528)
			(end -0.5715 0.2032)
			(stroke
				(width 0.1)
				(type default)
			)
			(layer "F.Fab")
		)
		(fp_line
			(start 0.5715 0.2032)
			(end 0.5715 3.3528)
			(stroke
				(width 0.1)
				(type default)
			)
			(layer "F.Fab")
		)
		(fp_line
			(start 0.5715 2.8575)
			(end 0.72644 2.8575)
			(stroke
				(width 0.1)
				(type default)
			)
			(layer "F.Fab")
		)
		(fp_line
			(start 0.5715 3.3528)
			(end -0.5715 3.3528)
			(stroke
				(width 0.1)
				(type default)
			)
			(layer "F.Fab")
		)
		(fp_line
			(start 0.72644 0.6985)
			(end 0.5715 0.6985)
			(stroke
				(width 0.1)
				(type default)
			)
			(layer "F.Fab")
		)
		(fp_line
			(start 1.524 2.05994)
			(end 1.524 1.49606)
			(stroke
				(width 0.1)
				(type default)
			)
			(layer "F.Fab")
		)
		(fp_arc
			(start 0.72644 0.6985)
			(mid 1.290388 0.932112)
			(end 1.524 1.49606)
			(stroke
				(width 0.1)
				(type default)
			)
			(layer "F.Fab")
		)
		(fp_arc
			(start 1.524 2.05994)
			(mid 1.290388 2.623888)
			(end 0.72644 2.8575)
			(stroke
				(width 0.1)
				(type default)
			)
			(layer "F.Fab")
		)
		(pad "1" smd rect
			(at 0 0)
			(size 1.524 1.524)
			(layers "F.Cu" "F.Mask" "F.Paste")
			(net "FP_LED_HDD_ACTIVITY_AND_N")
		)
		(pad "2" smd rect
			(at 0 3.556)
			(size 1.524 1.524)
			(layers "F.Cu" "F.Mask" "F.Paste")
			(net "FP_LED_HDD_ACTIVITY_AND_R_N")
		)
		(pad "3" smd rect
			(at -0.762 1.778)
			(size 0.889 0.889)
			(layers "F.Cu" "F.Mask" "F.Paste")
			(net "Net_6478")
		)
		(zone
			(layer "F.Cu")
			(hatch none 0.5)
			(connect_pads
				(clearance 0)
			)
			(min_thickness 0.25)
			(keepout
				(tracks allowed)
				(vias not_allowed)
				(pads allowed)
				(copperpour not_allowed)
				(footprints allowed)
			)
			(placement
				(enabled no)
				(sheetname "")
			)
			(fill
				(thermal_gap 0.5)
				(thermal_bridge_width 0.5)
				(island_removal_mode 0)
			)
			(polygon
				(pts
					(xy 500.4435 -149.0472) (xy 500.4435 -147.1168) (xy 499.3005 -147.1168) (xy 499.3005 -149.0472)
				)
			)
		)
	)
	(footprint ""
		(layer "F.Cu")
		(at 413.639 -21.971 180)
		(property "Reference" "R25W116"
			(at -0.8382 -0.67818 180)
			(unlocked yes)
			(layer "F.SilkS")
			(effects
				(font
					(size 0.4064 0.254)
					(thickness 0.1524)
				)
				(justify left)
			)
		)
		(property "Value" ""
			(at 0 0 180)
			(layer "F.Fab")
			(effects
				(font
					(size 1.27 1.27)
				)
			)
		)
		(duplicate_pad_numbers_are_jumpers no)
		(fp_poly
			(pts
				(xy -0.2794 -0.1016) (xy 0.2794 -0.1016) (xy 0.2794 0.9906) (xy -0.2794 0.9906)
			)
			(stroke
				(width 0)
				(type default)
			)
			(fill no)
			(layer "F.CrtYd")
		)
		(fp_line
			(start 0.2794 0.9906)
			(end 0.2794 -0.1016)
			(stroke
				(width 0.1)
				(type default)
			)
			(layer "F.Fab")
		)
		(fp_line
			(start 0.2794 -0.1016)
			(end -0.2794 -0.1016)
			(stroke
				(width 0.1)
				(type default)
			)
			(layer "F.Fab")
		)
		(fp_line
			(start -0.2794 0.9906)
			(end 0.2794 0.9906)
			(stroke
				(width 0.1)
				(type default)
			)
			(layer "F.Fab")
		)
		(fp_line
			(start -0.2794 -0.1016)
			(end -0.2794 0.9906)
			(stroke
				(width 0.1)
				(type default)
			)
			(layer "F.Fab")
		)
		(pad "1" smd rect
			(at 0 0 180)
			(size 0.508 0.508)
			(layers "F.Cu" "F.Mask" "F.Paste")
			(net "GND")
		)
		(pad "2" smd rect
			(at 0 0.889 180)
			(size 0.508 0.508)
			(layers "F.Cu" "F.Mask" "F.Paste")
			(net "UART_BMC_TXD5")
		)
		(zone
			(layer "F.Cu")
			(hatch none 0.5)
			(connect_pads
				(clearance 0)
			)
			(min_thickness 0.25)
			(keepout
				(tracks not_allowed)
				(vias allowed)
				(pads allowed)
				(copperpour not_allowed)
				(footprints allowed)
			)
			(placement
				(enabled no)
				(sheetname "")
			)
			(fill
				(thermal_gap 0.5)
				(thermal_bridge_width 0.5)
				(island_removal_mode 0)
			)
			(polygon
				(pts
					(xy 413.893 -22.606) (xy 413.385 -22.606) (xy 413.385 -22.225) (xy 413.893 -22.225)
				)
			)
		)
		(zone
			(layer "F.Cu")
			(hatch none 0.5)
			(connect_pads
				(clearance 0)
			)
			(min_thickness 0.25)
			(keepout
				(tracks allowed)
				(vias not_allowed)
				(pads allowed)
				(copperpour not_allowed)
				(footprints allowed)
			)
			(placement
				(enabled no)
				(sheetname "")
			)
			(fill
				(thermal_gap 0.5)
				(thermal_bridge_width 0.5)
				(island_removal_mode 0)
			)
			(polygon
				(pts
					(xy 413.893 -22.225) (xy 413.385 -22.225) (xy 413.385 -22.606) (xy 413.893 -22.606)
				)
			)
		)
	)
)
